#ISCELL
  pure_quanta quanta_title_block_c *
  *
#ISCELL
  standard offpage *
  page128_i1
#CELL
  pure_quanta q_res *
  page128_i10
#CELL
  pure_quanta q_res *
  page128_i11
#CELL
  pure_quanta q_res *
  page128_i12
#ISCELL
  standard offpage *
  page128_i2
#ISCELL
  standard offpage *
  page128_i3
#ISCELL
  standard offpage *
  page128_i30
#ISCELL
  standard offpage *
  page128_i31
#ISCELL
  standard offpage *
  page128_i32
#ISCELL
  standard offpage *
  page128_i33
#ISCELL
  standard offpage *
  page128_i4
#ISCELL
  standard offpage *
  page128_i44
#ISCELL
  standard offpage *
  page128_i45
#ISCELL
  standard offpage *
  page128_i46
#ISCELL
  standard offpage *
  page128_i47
#CELL
  pure_quanta q_res *
  page128_i48
#CELL
  pure_quanta q_res *
  page128_i49
#CELL
  pure_quanta q_res *
  page128_i50
#CELL
  pure_quanta q_res *
  page128_i51
#ISCELL
  standard offpage *
  page128_i68
#ISCELL
  standard offpage *
  page128_i69
#ISCELL
  standard offpage *
  page128_i70
#ISCELL
  standard offpage *
  page128_i71
#CELL
  pure_quanta q_res *
  page128_i77
#CELL
  pure_quanta q_res *
  page128_i78
#CELL
  pure_quanta q_res *
  page128_i79
#CELL
  pure_quanta q_res *
  page128_i80
#ISCELL
  logical_power universal_gnd *
  page128_i81
#CELL
  pure_quanta q_res *
  page128_i82
#CELL
  pure_quanta q_res *
  page128_i83
#ISCELL
  logical_power universal_gnd *
  page128_i84
#CELL
  pure_quanta q_res *
  page128_i85
#CELL
  pure_quanta q_res *
  page128_i86
#CELL
  pure_quanta q_res *
  page128_i9
